# BASEBOARD_FAB2 (Tioga Pass) — schematic netlist excerpt (pin names and nets, part order shuffled) for the footprints in the layout excerpt that follows; sources: Cadence DE-HDL packaged netlist, KiCad conversion of Wiwynn_Tioga_Pass_MB.brd

R8C25  RES  4.75K 1% CHIP  pkg 0402  page 133 : A = P3V3_STBY ; B = IRQ_PCH_NIC_ALERT_N
R8W4  RES  20.0 1% CHIP  pkg 0402  page 138 : A = SMB_HOST_STBY_LVC3_SDA ; B = SMB_HOST_STBY_LVC3_SDA_R5
C8P25  CAP  47UF 4V 20% X6S  pkg 0805  page 76 : A = PVCCIN_CPU1 ; B = GND

(kicad_pcb
	(version 20260206)
	(generator "pcbnew")
	(generator_version "10.0")
	(general
		(thickness 1.6)
		(legacy_teardrops no)
	)
	(paper "A4")
	(title_block
		(title "Wiwynn_Tioga_Pass_MB.brd")
		(comment 1 "Tioga Pass / footprints 3261-3263 of 4770")
	)
	(layers
		(0 "F.Cu" signal "TOP")
		(4 "In1.Cu" signal "L2GND")
		(6 "In2.Cu" signal "L3")
		(8 "In3.Cu" signal "L4GND")
		(10 "In4.Cu" signal "L5")
		(12 "In5.Cu" signal "L6GND")
		(14 "In6.Cu" signal "L7VCC")
		(16 "In7.Cu" signal "L8VCC")
		(18 "In8.Cu" signal "L9GND")
		(20 "In9.Cu" signal "L10")
		(22 "In10.Cu" signal "L11GND")
		(24 "In11.Cu" signal "L12")
		(26 "In12.Cu" signal "L13GND")
		(2 "B.Cu" signal "BOTTOM")
		(9 "F.Adhes" user "F.Adhesive")
		(11 "B.Adhes" user "B.Adhesive")
		(13 "F.Paste" user "Package Geometry/Pastemask Top")
		(15 "B.Paste" user "Package Geometry/Pastemask Bottom")
		(5 "F.SilkS" user "Ref Des/Silkscreen Top")
		(7 "B.SilkS" user "Ref Des/Silkscreen Bottom")
		(1 "F.Mask" user "Board Geometry/Soldermask Top")
		(3 "B.Mask" user "Board Geometry/Soldermask Bottom")
		(17 "Dwgs.User" user "User.Drawings")
		(19 "Cmts.User" user "User.Comments")
		(21 "Eco1.User" user "User.Eco1")
		(23 "Eco2.User" user "User.Eco2")
		(25 "Edge.Cuts" user "Board Geometry/Outline")
		(27 "Margin" user)
		(31 "F.CrtYd" user "Package Geometry/Place Bound Top")
		(29 "B.CrtYd" user "Package Geometry/Place Bound Bottom")
		(35 "F.Fab" user "Ref Des/Assembly Top")
		(33 "B.Fab" user "Ref Des/Assembly Bottom")
	)
	(footprint ""
		(layer "B.Cu")
		(at 447.136266 -22.269196 -90)
		(property "Reference" "R8W4"
			(at 0.8382 -0.67818 270)
			(unlocked yes)
			(layer "B.SilkS")
			(effects
				(font
					(size 0.4064 0.254)
					(thickness 0.1524)
				)
				(justify left mirror)
			)
		)
		(property "Value" ""
			(at 0 0 90)
			(layer "B.Fab")
			(effects
				(font
					(size 1.27 1.27)
				)
				(justify mirror)
			)
		)
		(duplicate_pad_numbers_are_jumpers no)
		(fp_poly
			(pts
				(xy 0.2794 -0.1016) (xy -0.2794 -0.1016) (xy -0.2794 0.9906) (xy 0.2794 0.9906)
			)
			(stroke
				(width 0)
				(type default)
			)
			(fill no)
			(layer "B.CrtYd")
		)
		(fp_line
			(start -0.2794 0.9906)
			(end -0.2794 -0.1016)
			(stroke
				(width 0.1)
				(type default)
			)
			(layer "B.Fab")
		)
		(fp_line
			(start 0.2794 0.9906)
			(end -0.2794 0.9906)
			(stroke
				(width 0.1)
				(type default)
			)
			(layer "B.Fab")
		)
		(fp_line
			(start -0.2794 -0.1016)
			(end 0.2794 -0.1016)
			(stroke
				(width 0.1)
				(type default)
			)
			(layer "B.Fab")
		)
		(fp_line
			(start 0.2794 -0.1016)
			(end 0.2794 0.9906)
			(stroke
				(width 0.1)
				(type default)
			)
			(layer "B.Fab")
		)
		(pad "1" smd rect
			(at 0 0 90)
			(size 0.508 0.508)
			(layers "B.Cu" "B.Mask" "B.Paste")
			(net "SMB_HOST_STBY_LVC3_SDA")
		)
		(pad "2" smd rect
			(at 0 0.889 90)
			(size 0.508 0.508)
			(layers "B.Cu" "B.Mask" "B.Paste")
			(net "SMB_HOST_STBY_LVC3_SDA_R5")
		)
		(zone
			(layer "B.Cu")
			(hatch none 0.5)
			(connect_pads
				(clearance 0)
			)
			(min_thickness 0.25)
			(keepout
				(tracks not_allowed)
				(vias allowed)
				(pads allowed)
				(copperpour not_allowed)
				(footprints allowed)
			)
			(placement
				(enabled no)
				(sheetname "")
			)
			(fill
				(thermal_gap 0.5)
				(thermal_bridge_width 0.5)
				(island_removal_mode 0)
			)
			(polygon
				(pts
					(xy 446.501266 -22.015196) (xy 446.501266 -22.523196) (xy 446.882266 -22.523196) (xy 446.882266 -22.015196)
				)
			)
		)
		(zone
			(layer "B.Cu")
			(hatch none 0.5)
			(connect_pads
				(clearance 0)
			)
			(min_thickness 0.25)
			(keepout
				(tracks allowed)
				(vias not_allowed)
				(pads allowed)
				(copperpour not_allowed)
				(footprints allowed)
			)
			(placement
				(enabled no)
				(sheetname "")
			)
			(fill
				(thermal_gap 0.5)
				(thermal_bridge_width 0.5)
				(island_removal_mode 0)
			)
			(polygon
				(pts
					(xy 446.882266 -22.015196) (xy 446.882266 -22.523196) (xy 446.501266 -22.523196) (xy 446.501266 -22.015196)
				)
			)
		)
	)
	(footprint ""
		(layer "B.Cu")
		(at 404.5585 -98.679 -90)
		(property "Reference" "R8C25"
			(at 0 0 90)
			(layer "B.SilkS")
			(hide yes)
			(effects
				(font
					(size 1.27 1.27)
				)
				(justify mirror)
			)
		)
		(property "Value" ""
			(at 0 0 90)
			(layer "B.Fab")
			(effects
				(font
					(size 1.27 1.27)
				)
				(justify mirror)
			)
		)
		(duplicate_pad_numbers_are_jumpers no)
		(fp_poly
			(pts
				(xy 0.2794 -0.1016) (xy -0.2794 -0.1016) (xy -0.2794 0.9906) (xy 0.2794 0.9906)
			)
			(stroke
				(width 0)
				(type default)
			)
			(fill no)
			(layer "B.CrtYd")
		)
		(fp_line
			(start -0.2794 0.9906)
			(end -0.2794 -0.1016)
			(stroke
				(width 0.1)
				(type default)
			)
			(layer "B.Fab")
		)
		(fp_line
			(start 0.2794 0.9906)
			(end -0.2794 0.9906)
			(stroke
				(width 0.1)
				(type default)
			)
			(layer "B.Fab")
		)
		(fp_line
			(start -0.2794 -0.1016)
			(end 0.2794 -0.1016)
			(stroke
				(width 0.1)
				(type default)
			)
			(layer "B.Fab")
		)
		(fp_line
			(start 0.2794 -0.1016)
			(end 0.2794 0.9906)
			(stroke
				(width 0.1)
				(type default)
			)
			(layer "B.Fab")
		)
		(pad "1" smd rect
			(at 0 0 90)
			(size 0.508 0.508)
			(layers "B.Cu" "B.Mask" "B.Paste")
			(net "P3V3_STBY")
		)
		(pad "2" smd rect
			(at 0 0.889 90)
			(size 0.508 0.508)
			(layers "B.Cu" "B.Mask" "B.Paste")
			(net "IRQ_PCH_NIC_ALERT_N")
		)
		(zone
			(layer "B.Cu")
			(hatch none 0.5)
			(connect_pads
				(clearance 0)
			)
			(min_thickness 0.25)
			(keepout
				(tracks not_allowed)
				(vias allowed)
				(pads allowed)
				(copperpour not_allowed)
				(footprints allowed)
			)
			(placement
				(enabled no)
				(sheetname "")
			)
			(fill
				(thermal_gap 0.5)
				(thermal_bridge_width 0.5)
				(island_removal_mode 0)
			)
			(polygon
				(pts
					(xy 403.9235 -98.425) (xy 403.9235 -98.933) (xy 404.3045 -98.933) (xy 404.3045 -98.425)
				)
			)
		)
		(zone
			(layer "B.Cu")
			(hatch none 0.5)
			(connect_pads
				(clearance 0)
			)
			(min_thickness 0.25)
			(keepout
				(tracks allowed)
				(vias not_allowed)
				(pads allowed)
				(copperpour not_allowed)
				(footprints allowed)
			)
			(placement
				(enabled no)
				(sheetname "")
			)
			(fill
				(thermal_gap 0.5)
				(thermal_bridge_width 0.5)
				(island_removal_mode 0)
			)
			(polygon
				(pts
					(xy 404.3045 -98.425) (xy 404.3045 -98.933) (xy 403.9235 -98.933) (xy 403.9235 -98.425)
				)
			)
		)
	)
	(footprint ""
		(layer "B.Cu")
		(at 100.863654 -73.51014)
		(property "Reference" "C8P25"
			(at 0 0 0)
			(layer "B.SilkS")
			(hide yes)
			(effects
				(font
					(size 1.27 1.27)
				)
				(justify mirror)
			)
		)
		(property "Value" ""
			(at 0 0 0)
			(layer "B.Fab")
			(effects
				(font
					(size 1.27 1.27)
				)
				(justify mirror)
			)
		)
		(duplicate_pad_numbers_are_jumpers no)
		(fp_poly
			(pts
				(xy 0.7239 -0.2159) (xy -0.7239 -0.2159) (xy -0.7239 1.9939) (xy 0.7239 1.9939)
			)
			(stroke
				(width 0)
				(type default)
			)
			(fill no)
			(layer "B.CrtYd")
		)
		(fp_line
			(start -0.7239 -0.2159)
			(end 0.7239 -0.2159)
			(stroke
				(width 0.1)
				(type default)
			)
			(layer "B.Fab")
		)
		(fp_line
			(start -0.7239 1.9939)
			(end -0.7239 -0.2159)
			(stroke
				(width 0.1)
				(type default)
			)
			(layer "B.Fab")
		)
		(fp_line
			(start 0.7239 -0.2159)
			(end 0.7239 1.9939)
			(stroke
				(width 0.1)
				(type default)
			)
			(layer "B.Fab")
		)
		(fp_line
			(start 0.7239 1.9939)
			(end -0.7239 1.9939)
			(stroke
				(width 0.1)
				(type default)
			)
			(layer "B.Fab")
		)
		(pad "1" smd rect
			(at 0 0 180)
			(size 1.27 1.016)
			(layers "B.Cu" "B.Mask" "B.Paste")
			(net "PVCCIN_CPU1")
		)
		(pad "2" smd rect
			(at 0 1.778 180)
			(size 1.27 1.016)
			(layers "B.Cu" "B.Mask" "B.Paste")
			(net "GND")
		)
		(zone
			(layer "B.Cu")
			(hatch none 0.5)
			(connect_pads
				(clearance 0)
			)
			(min_thickness 0.25)
			(keepout
				(tracks not_allowed)
				(vias allowed)
				(pads allowed)
				(copperpour not_allowed)
				(footprints allowed)
			)
			(placement
				(enabled no)
				(sheetname "")
			)
			(fill
				(thermal_gap 0.5)
				(thermal_bridge_width 0.5)
				(island_removal_mode 0)
			)
			(polygon
				(pts
					(xy 101.498654 -73.00214) (xy 100.228654 -73.00214) (xy 100.228654 -72.24014) (xy 101.498654 -72.24014)
				)
			)
		)
	)
)
